# BASEBOARD_FAB2 (Tioga Pass) — schematic netlist excerpt (pin names and nets, part order shuffled) for the footprints in the layout excerpt that follows; sources: Cadence DE-HDL packaged netlist, KiCad conversion of Wiwynn_Tioga_Pass_MB.brd

C7B23  CAP_A  22.0UF 4V 20% X6S  pkg 0603V  page 131 : A = P1V05_PCH_STBY ; B = GND
R4D23  RES  27.4 1% CHIP  pkg 0402  page 103 : A = CLK_100M_CPU1_RC_REFCLK1_R_DP ; B = CLK_100M_CPU1_RC_REFCLK1_DP
R4B8  RES  7.87K 1.0% CHIP  pkg 0402  page 234 : A = VR_COMP_RC_PVPP_KLM ; B = VR_FB_PVPP_KLM

(kicad_pcb
	(version 20260206)
	(generator "pcbnew")
	(generator_version "10.0")
	(general
		(thickness 1.6)
		(legacy_teardrops no)
	)
	(paper "A4")
	(title_block
		(title "Wiwynn_Tioga_Pass_MB.brd")
		(comment 1 "Tioga Pass / footprints 575-577 of 4770")
	)
	(layers
		(0 "F.Cu" signal "TOP")
		(4 "In1.Cu" signal "L2GND")
		(6 "In2.Cu" signal "L3")
		(8 "In3.Cu" signal "L4GND")
		(10 "In4.Cu" signal "L5")
		(12 "In5.Cu" signal "L6GND")
		(14 "In6.Cu" signal "L7VCC")
		(16 "In7.Cu" signal "L8VCC")
		(18 "In8.Cu" signal "L9GND")
		(20 "In9.Cu" signal "L10")
		(22 "In10.Cu" signal "L11GND")
		(24 "In11.Cu" signal "L12")
		(26 "In12.Cu" signal "L13GND")
		(2 "B.Cu" signal "BOTTOM")
		(9 "F.Adhes" user "F.Adhesive")
		(11 "B.Adhes" user "B.Adhesive")
		(13 "F.Paste" user "Package Geometry/Pastemask Top")
		(15 "B.Paste" user "Package Geometry/Pastemask Bottom")
		(5 "F.SilkS" user "Ref Des/Silkscreen Top")
		(7 "B.SilkS" user "Ref Des/Silkscreen Bottom")
		(1 "F.Mask" user "Board Geometry/Soldermask Top")
		(3 "B.Mask" user "Board Geometry/Soldermask Bottom")
		(17 "Dwgs.User" user "User.Drawings")
		(19 "Cmts.User" user "User.Comments")
		(21 "Eco1.User" user "User.Eco1")
		(23 "Eco2.User" user "User.Eco2")
		(25 "Edge.Cuts" user "Board Geometry/Outline")
		(27 "Margin" user)
		(31 "F.CrtYd" user "Package Geometry/Place Bound Top")
		(29 "B.CrtYd" user "Package Geometry/Place Bound Bottom")
		(35 "F.Fab" user "Ref Des/Assembly Top")
		(33 "B.Fab" user "Ref Des/Assembly Bottom")
	)
	(footprint ""
		(layer "F.Cu")
		(at 372.0084 -131.7498 180)
		(property "Reference" "C7B23"
			(at 0 0 180)
			(layer "F.SilkS")
			(hide yes)
			(effects
				(font
					(size 1.27 1.27)
				)
			)
		)
		(property "Value" ""
			(at 0 0 180)
			(layer "F.Fab")
			(effects
				(font
					(size 1.27 1.27)
				)
			)
		)
		(duplicate_pad_numbers_are_jumpers no)
		(fp_poly
			(pts
				(xy -0.4953 -0.2032) (xy 0.4953 -0.2032) (xy 0.4953 1.6002) (xy -0.4953 1.6002)
			)
			(stroke
				(width 0)
				(type default)
			)
			(fill no)
			(layer "F.CrtYd")
		)
		(fp_line
			(start 0.4953 1.6002)
			(end -0.4953 1.6002)
			(stroke
				(width 0.1)
				(type default)
			)
			(layer "F.Fab")
		)
		(fp_line
			(start 0.4953 -0.2032)
			(end 0.4953 1.6002)
			(stroke
				(width 0.1)
				(type default)
			)
			(layer "F.Fab")
		)
		(fp_line
			(start -0.4953 1.6002)
			(end -0.4953 -0.2032)
			(stroke
				(width 0.1)
				(type default)
			)
			(layer "F.Fab")
		)
		(fp_line
			(start -0.4953 -0.2032)
			(end 0.4953 -0.2032)
			(stroke
				(width 0.1)
				(type default)
			)
			(layer "F.Fab")
		)
		(pad "1" smd rect
			(at 0 0 180)
			(size 0.762 0.889)
			(layers "F.Cu" "F.Mask" "F.Paste")
			(net "P1V05_PCH_STBY")
		)
		(pad "2" smd rect
			(at 0 1.397 180)
			(size 0.762 0.889)
			(layers "F.Cu" "F.Mask" "F.Paste")
			(net "GND")
		)
		(zone
			(layer "F.Cu")
			(hatch none 0.5)
			(connect_pads
				(clearance 0)
			)
			(min_thickness 0.25)
			(keepout
				(tracks not_allowed)
				(vias allowed)
				(pads allowed)
				(copperpour not_allowed)
				(footprints allowed)
			)
			(placement
				(enabled no)
				(sheetname "")
			)
			(fill
				(thermal_gap 0.5)
				(thermal_bridge_width 0.5)
				(island_removal_mode 0)
			)
			(polygon
				(pts
					(xy 372.3894 -132.1943) (xy 371.6274 -132.1943) (xy 371.6274 -132.7023) (xy 372.3894 -132.7023)
				)
			)
		)
	)
	(footprint ""
		(layer "F.Cu")
		(at 163.576 -77.978 -90)
		(property "Reference" "R4D23"
			(at 0 0 270)
			(layer "F.SilkS")
			(hide yes)
			(effects
				(font
					(size 1.27 1.27)
				)
			)
		)
		(property "Value" ""
			(at 0 0 270)
			(layer "F.Fab")
			(effects
				(font
					(size 1.27 1.27)
				)
			)
		)
		(duplicate_pad_numbers_are_jumpers no)
		(fp_poly
			(pts
				(xy -0.2794 -0.1016) (xy 0.2794 -0.1016) (xy 0.2794 0.9906) (xy -0.2794 0.9906)
			)
			(stroke
				(width 0)
				(type default)
			)
			(fill no)
			(layer "F.CrtYd")
		)
		(fp_line
			(start -0.2794 0.9906)
			(end 0.2794 0.9906)
			(stroke
				(width 0.1)
				(type default)
			)
			(layer "F.Fab")
		)
		(fp_line
			(start 0.2794 0.9906)
			(end 0.2794 -0.1016)
			(stroke
				(width 0.1)
				(type default)
			)
			(layer "F.Fab")
		)
		(fp_line
			(start -0.2794 -0.1016)
			(end -0.2794 0.9906)
			(stroke
				(width 0.1)
				(type default)
			)
			(layer "F.Fab")
		)
		(fp_line
			(start 0.2794 -0.1016)
			(end -0.2794 -0.1016)
			(stroke
				(width 0.1)
				(type default)
			)
			(layer "F.Fab")
		)
		(pad "1" smd rect
			(at 0 0 270)
			(size 0.508 0.508)
			(layers "F.Cu" "F.Mask" "F.Paste")
			(net "CLK_100M_CPU1_RC_REFCLK1_R_DP")
		)
		(pad "2" smd rect
			(at 0 0.889 270)
			(size 0.508 0.508)
			(layers "F.Cu" "F.Mask" "F.Paste")
			(net "CLK_100M_CPU1_RC_REFCLK1_DP")
		)
		(zone
			(layer "F.Cu")
			(hatch none 0.5)
			(connect_pads
				(clearance 0)
			)
			(min_thickness 0.25)
			(keepout
				(tracks not_allowed)
				(vias allowed)
				(pads allowed)
				(copperpour not_allowed)
				(footprints allowed)
			)
			(placement
				(enabled no)
				(sheetname "")
			)
			(fill
				(thermal_gap 0.5)
				(thermal_bridge_width 0.5)
				(island_removal_mode 0)
			)
			(polygon
				(pts
					(xy 162.941 -78.232) (xy 162.941 -77.724) (xy 163.322 -77.724) (xy 163.322 -78.232)
				)
			)
		)
		(zone
			(layer "F.Cu")
			(hatch none 0.5)
			(connect_pads
				(clearance 0)
			)
			(min_thickness 0.25)
			(keepout
				(tracks allowed)
				(vias not_allowed)
				(pads allowed)
				(copperpour not_allowed)
				(footprints allowed)
			)
			(placement
				(enabled no)
				(sheetname "")
			)
			(fill
				(thermal_gap 0.5)
				(thermal_bridge_width 0.5)
				(island_removal_mode 0)
			)
			(polygon
				(pts
					(xy 163.322 -78.232) (xy 163.322 -77.724) (xy 162.941 -77.724) (xy 162.941 -78.232)
				)
			)
		)
	)
	(footprint ""
		(layer "F.Cu")
		(at 175.133 -131.3815 180)
		(property "Reference" "R4B8"
			(at 0 0 180)
			(layer "F.SilkS")
			(hide yes)
			(effects
				(font
					(size 1.27 1.27)
				)
			)
		)
		(property "Value" ""
			(at 0 0 180)
			(layer "F.Fab")
			(effects
				(font
					(size 1.27 1.27)
				)
			)
		)
		(duplicate_pad_numbers_are_jumpers no)
		(fp_poly
			(pts
				(xy -0.2794 -0.1016) (xy 0.2794 -0.1016) (xy 0.2794 0.9906) (xy -0.2794 0.9906)
			)
			(stroke
				(width 0)
				(type default)
			)
			(fill no)
			(layer "F.CrtYd")
		)
		(fp_line
			(start 0.2794 0.9906)
			(end 0.2794 -0.1016)
			(stroke
				(width 0.1)
				(type default)
			)
			(layer "F.Fab")
		)
		(fp_line
			(start 0.2794 -0.1016)
			(end -0.2794 -0.1016)
			(stroke
				(width 0.1)
				(type default)
			)
			(layer "F.Fab")
		)
		(fp_line
			(start -0.2794 0.9906)
			(end 0.2794 0.9906)
			(stroke
				(width 0.1)
				(type default)
			)
			(layer "F.Fab")
		)
		(fp_line
			(start -0.2794 -0.1016)
			(end -0.2794 0.9906)
			(stroke
				(width 0.1)
				(type default)
			)
			(layer "F.Fab")
		)
		(pad "1" smd rect
			(at 0 0 180)
			(size 0.508 0.508)
			(layers "F.Cu" "F.Mask" "F.Paste")
			(net "VR_COMP_RC_PVPP_KLM")
		)
		(pad "2" smd rect
			(at 0 0.889 180)
			(size 0.508 0.508)
			(layers "F.Cu" "F.Mask" "F.Paste")
			(net "VR_FB_PVPP_KLM")
		)
		(zone
			(layer "F.Cu")
			(hatch none 0.5)
			(connect_pads
				(clearance 0)
			)
			(min_thickness 0.25)
			(keepout
				(tracks not_allowed)
				(vias allowed)
				(pads allowed)
				(copperpour not_allowed)
				(footprints allowed)
			)
			(placement
				(enabled no)
				(sheetname "")
			)
			(fill
				(thermal_gap 0.5)
				(thermal_bridge_width 0.5)
				(island_removal_mode 0)
			)
			(polygon
				(pts
					(xy 175.387 -132.0165) (xy 174.879 -132.0165) (xy 174.879 -131.6355) (xy 175.387 -131.6355)
				)
			)
		)
		(zone
			(layer "F.Cu")
			(hatch none 0.5)
			(connect_pads
				(clearance 0)
			)
			(min_thickness 0.25)
			(keepout
				(tracks allowed)
				(vias not_allowed)
				(pads allowed)
				(copperpour not_allowed)
				(footprints allowed)
			)
			(placement
				(enabled no)
				(sheetname "")
			)
			(fill
				(thermal_gap 0.5)
				(thermal_bridge_width 0.5)
				(island_removal_mode 0)
			)
			(polygon
				(pts
					(xy 175.387 -131.6355) (xy 174.879 -131.6355) (xy 174.879 -132.0165) (xy 175.387 -132.0165)
				)
			)
		)
	)
)
